# Lightning_PTB_SI constraints.xls — Net Rule by Layer (si-constraints)
| Project Name: 14629-1 |  |  |  |  |  |  |  |  |  |  |  |  |  |  |  |  |  |
| Project Path: C:\Users\<user>\Desktop\+-5%\14629-1.db |  |  |  |  |  |  |  |  |  |  |  |  |  |  |  |  |  |
| Net Name | Group Name | Type | Layer | T_W(X) | P-P | P-V | P-T | V-V | V-T | T_T(Y) | P-F | V-F | T-F | F-F | T_T(Z) | Ohm | Ref Layer |
| I2C_C_BUF_EN | I2C_BUS | BUS | 1 | 5.5 | 5 | 10 | 5 | 12 | 5 | 15 | 12 | 12 | 12 | 12 |  |  |  |
| I2C_C_BUF_READY | I2C_BUS | BUS | 1 | 5.5 | 5 | 10 | 5 | 12 | 5 | 15 | 12 | 12 | 12 | 12 |  |  |  |
| I2C_C_BUF_SCL | I2C_BUS | BUS | 1 | 5.5 | 5 | 10 | 5 | 12 | 5 | 15 | 12 | 12 | 12 | 12 |  |  |  |
| I2C_C_BUF_SCL_CONN | I2C_BUS | BUS | 1 | 5.5 | 5 | 10 | 5 | 12 | 5 | 15 | 12 | 12 | 12 | 12 |  |  |  |
| I2C_C_BUF_SCLIN | I2C_BUS | BUS | 1 | 5.5 | 5 | 10 | 5 | 12 | 5 | 15 | 12 | 12 | 12 | 12 |  |  |  |
| I2C_C_BUF_SCLOUT | I2C_BUS | BUS | 1 | 5.5 | 5 | 10 | 5 | 12 | 5 | 15 | 12 | 12 | 12 | 12 |  |  |  |
| I2C_C_BUF_SDA | I2C_BUS | BUS | 1 | 5.5 | 5 | 10 | 5 | 12 | 5 | 15 | 12 | 12 | 12 | 12 |  |  |  |
| I2C_C_BUF_SDA_CONN | I2C_BUS | BUS | 1 | 5.5 | 5 | 10 | 5 | 12 | 5 | 15 | 12 | 12 | 12 | 12 |  |  |  |
| I2C_C_BUF_SDAIN | I2C_BUS | BUS | 1 | 5.5 | 5 | 10 | 5 | 12 | 5 | 15 | 12 | 12 | 12 | 12 |  |  |  |
| I2C_C_BUF_SDAOUT | I2C_BUS | BUS | 1 | 5.5 | 5 | 10 | 5 | 12 | 5 | 15 | 12 | 12 | 12 | 12 |  |  |  |
| I2C_C_SCL | I2C_BUS | BUS | 1 | 5.5 | 5 | 10 | 5 | 12 | 5 | 15 | 12 | 12 | 12 | 12 |  |  |  |
| I2C_C_SDA | I2C_BUS | BUS | 1 | 5.5 | 5 | 10 | 5 | 12 | 5 | 15 | 12 | 12 | 12 | 12 |  |  |  |
| STRADDLE_I2C_C_SCL | I2C_BUS | BUS | 1 | 5.5 | 5 | 10 | 5 | 12 | 5 | 15 | 12 | 12 | 12 | 12 |  |  |  |
| STRADDLE_I2C_C_SDA | I2C_BUS | BUS | 1 | 5.5 | 5 | 10 | 5 | 12 | 5 | 15 | 12 | 12 | 12 | 12 |  |  |  |
| FCB_HW_REV | NORAML_BUS | BUS | 1 | 5.5 | 5 | 10 | 5 | 12 | 5 | 12 | 12 | 12 | 12 | 12 |  |  |  |
| IR_SWITCH_E | NORAML_BUS | BUS | 1 | 5.5 | 5 | 10 | 5 | 12 | 5 | 12 | 12 | 12 | 12 | 12 |  |  |  |
| PEER_1A&2A_HB | NORAML_BUS | BUS | 1 | 5.5 | 5 | 10 | 5 | 12 | 5 | 12 | 12 | 12 | 12 | 12 |  |  |  |
| PEER_1B&2B_HB | NORAML_BUS | BUS | 1 | 5.5 | 5 | 10 | 5 | 12 | 5 | 12 | 12 | 12 | 12 | 12 |  |  |  |
| PEER_TRAY_PRESENT | NORAML_BUS | BUS | 1 | 5.5 | 5 | 10 | 5 | 12 | 5 | 12 | 12 | 12 | 12 | 12 |  |  |  |
| PWM_EXP_A | NORAML_BUS | BUS | 1 | 5.5 | 5 | 10 | 5 | 12 | 5 | 12 | 12 | 12 | 12 | 12 |  |  |  |
| PWM_EXP_A_OUT | NORAML_BUS | BUS | 1 | 5.5 | 5 | 10 | 5 | 12 | 5 | 12 | 12 | 12 | 12 | 12 |  |  |  |
| PWM_EXP_B | NORAML_BUS | BUS | 1 | 5.5 | 5 | 10 | 5 | 12 | 5 | 12 | 12 | 12 | 12 | 12 |  |  |  |
| PWM_EXP_B_OUT | NORAML_BUS | BUS | 1 | 5.5 | 5 | 10 | 5 | 12 | 5 | 12 | 12 | 12 | 12 | 12 |  |  |  |
| SD_LATCH_RELEASE | NORAML_BUS | BUS | 1 | 5.5 | 5 | 10 | 5 | 12 | 5 | 12 | 12 | 12 | 12 | 12 |  |  |  |
| SELF_1A&2A_HB | NORAML_BUS | BUS | 1 | 5.5 | 5 | 10 | 5 | 12 | 5 | 12 | 12 | 12 | 12 | 12 |  |  |  |
| SELF_1B&2B_HB | NORAML_BUS | BUS | 1 | 5.5 | 5 | 10 | 5 | 12 | 5 | 12 | 12 | 12 | 12 | 12 |  |  |  |
| SELF_TRAY_PRESENT | NORAML_BUS | BUS | 1 | 5.5 | 5 | 10 | 5 | 12 | 5 | 12 | 12 | 12 | 12 | 12 |  |  |  |
| TPS2490_DISABLE | NORAML_BUS | BUS | 1 | 5.5 | 5 | 10 | 5 | 12 | 5 | 12 | 12 | 12 | 12 | 12 |  |  |  |
| TPS2490_EN1 | NORAML_BUS | BUS | 1 | 5.5 | 5 | 10 | 5 | 12 | 5 | 12 | 12 | 12 | 12 | 12 |  |  |  |
| TPS2490_EN2 | NORAML_BUS | BUS | 1 | 5.5 | 5 | 10 | 5 | 12 | 5 | 12 | 12 | 12 | 12 | 12 |  |  |  |
| TPS2490_LED | NORAML_BUS | BUS | 1 | 5.5 | 5 | 10 | 5 | 12 | 5 | 12 | 12 | 12 | 12 | 12 |  |  |  |
| TRAY_ID | NORAML_BUS | BUS | 1 | 5.5 | 5 | 10 | 5 | 12 | 5 | 12 | 12 | 12 | 12 | 12 |  |  |  |
| TRAY_MOSFET_G | NORAML_BUS | BUS | 1 | 5.5 | 5 | 10 | 5 | 12 | 5 | 12 | 12 | 12 | 12 | 12 |  |  |  |
| TRAY_PRESENT_OUT_NET_B | NORAML_BUS | BUS | 1 | 5.5 | 5 | 10 | 5 | 12 | 5 | 12 | 12 | 12 | 12 | 12 |  |  |  |
| GND | POWER_BUS_1600MIL | BUS | 1 | 1600 | 5 | 10 | 5 | 12 | 5 | 12 | 12 | 12 | 12 | 12 |  |  |  |
| P12V | POWER_BUS_1600MIL | BUS | 1 | 1600 | 5 | 10 | 5 | 12 | 5 | 12 | 12 | 12 | 12 | 12 |  |  |  |
| DETECTOR_C | POWER_BUS_40MIL | BUS | 1 | 40 | 5 | 10 | 5 | 12 | 5 | 12 | 12 | 12 | 12 | 12 |  |  |  |
| EMITTER_K | POWER_BUS_40MIL | BUS | 1 | 40 | 5 | 10 | 5 | 12 | 5 | 12 | 12 | 12 | 12 | 12 |  |  |  |
| P3V3 | POWER_BUS_40MIL | BUS | 1 | 40 | 5 | 10 | 5 | 12 | 5 | 12 | 12 | 12 | 12 | 12 |  |  |  |
| P5VA | POWER_BUS_40MIL | BUS | 1 | 40 | 5 | 10 | 5 | 12 | 5 | 12 | 12 | 12 | 12 | 12 |  |  |  |
